FILE_TYPE = CONNECTIVITY;
{Allegro Design Entry HDL 17.4-2019 S026 (4007227) 1/17/2022}
"PAGE_NUMBER" = 302;
0"NC";
1"P12V_PSU\g";
2"GND\g";
3"P12V_AUX\g";
4"P12V_MAIN_R\g";
5"P12V_MAIN_R_0\g";
6"P12V_HSC_GATE_G1";
7"P12V_HSC_GATE_G2";
8"P12V_HSC_GATE_G3";
9"P12V_HSC_GATE_G4";
10"P12V_HSC_GATE_G5";
11"P12V_HSC_GATE2";
12"P12V_HSC_GATE_G6";
13"MB0_CM_GATE_G0";
14"P12V_HSC_SENSE2_R1_P";
15"P12V_HSC_SENSE2_R3_P";
16"P12V_HSC_SENSE2_R2_N";
17"P12V_HSC_SENSE1_N";
18"P12V_HSC_SENSE2_R1_N";
19"P12V_HSC_SENSE2_R3_N";
20"P12V_HSC_SENSE2_R4_N";
21"P12V_HSC_SENSE1_P";
22"P12V_HSC_SENSE2_R2_P";
23"P12V_HSC_SENSE2_R3_P";
24"P12V_HSC_SENSE2_R4_P";
25"P12V_HSC_SENSE2_N";
26"P12V_HSC_SENSE2_P";
27"P12V_HSC_SENSE2_R1_N";
28"P12V_HSC_SENSE2_R2_N";
29"P12V_HSC_SENSE2_R3_N";
30"P12V_HSC_SENSE2_R4_N";
31"P12V_HSC_ADC_N";
32"P12V_HSC_ADC_P";
33"P12V_HSC_SENSE1_P";
34"P12V_HSC_SENSE2_R4_P";
35"P12V_HSC_SENSE2_R3_P";
36"P12V_HSC_SENSE2_R2_P";
37"P12V_HSC_SENSE2_R1_P";
38"P12V_HSC_SENSE2_R2_N";
39"P12V_HSC_SENSE2_R3_N";
40"P12V_HSC_SENSE2_R4_N";
41"P12V_HSC_SENSE1_N";
42"P12V_HSC_SENSE2_R1_P";
43"P12V_HSC_SENSE2_R1_N";
44"P12V_HSC_SENSE2_R2_P";
45"P12V_HSC_SENSE2_R4_P";
46"P12V_HSC_GATE_RC";
47"P12V_HSC_GATE1";
%"Q_RES"
"1","(-8275,4375)","0","pure_quanta","I15";
;
LOCATION"PR2513"
$SEC"1"
CDS_SEC"1"
MATERIAL"CHIP"
ROOM"HSC BOM2"
TOLERANCE"1%"
VALUE"1"
PART_NUMBER"CS-1002FB04"
PACK_TYPE"0402LF"
WATTAGE"1/16W"
CDS_LIB"pure_quanta";
"B"
$PN"2"34;
"A"
$PN"1"32;
%"Q_RES"
"1","(-8275,4475)","0","pure_quanta","I16";
;
LOCATION"PR2512"
$SEC"1"
CDS_SEC"1"
VALUE"1"
ROOM"HSC BOM2"
MATERIAL"CHIP"
TOLERANCE"1%"
PART_NUMBER"CS-1002FB04"
WATTAGE"1/16W"
PACK_TYPE"0402LF"
CDS_LIB"pure_quanta";
"B"
$PN"2"35;
"A"
$PN"1"32;
%"Q_RES"
"1","(-8275,4575)","0","pure_quanta","I17";
;
LOCATION"PR2511"
$SEC"1"
CDS_SEC"1"
TOLERANCE"1%"
ROOM"HSC BOM2"
MATERIAL"CHIP"
VALUE"1"
PART_NUMBER"CS-1002FB04"
WATTAGE"1/16W"
PACK_TYPE"0402LF"
CDS_LIB"pure_quanta";
"B"
$PN"2"36;
"A"
$PN"1"32;
%"Q_RES"
"1","(-8275,4675)","0","pure_quanta","I18";
;
LOCATION"PR2510"
$SEC"1"
CDS_SEC"1"
TOLERANCE"1%"
ROOM"HSC BOM2"
MATERIAL"CHIP"
VALUE"1"
PART_NUMBER"CS-1002FB04"
WATTAGE"1/16W"
PACK_TYPE"0402LF"
CDS_LIB"pure_quanta";
"B"
$PN"2"37;
"A"
$PN"1"32;
%"Q_RES"
"2","(-6550,1575)","0","pure_quanta","I27";
;
LOCATION"PR2528"
$SEC"1"
CDS_SEC"1"
ROOM"HSC BOM2"
VALUE"10"
WATTAGE"1/16W"
MATERIAL"CHIP"
TOLERANCE"1%"
PACK_TYPE"0402LF"
PART_NUMBER"CS01002FB07"
CDS_LIB"pure_quanta";
"A"
$PN"1"6;
"B"
$PN"2"11;
%"Q_RES"
"2","(-5675,1575)","0","pure_quanta","I28";
;
LOCATION"PR2529"
$SEC"1"
CDS_SEC"1"
ROOM"HSC BOM2"
TOLERANCE"1%"
MATERIAL"CHIP"
VALUE"10"
WATTAGE"1/16W"
PACK_TYPE"0402LF"
PART_NUMBER"CS01002FB07"
CDS_LIB"pure_quanta";
"A"
$PN"1"7;
"B"
$PN"2"11;
%"MOSFET_NCH_1D3S"
"1","(-6200,2275)","6","pure_quanta","I29";
;
LOCATION"PPQ5"
$SEC"1"
CDS_SEC"1"
ROOM"HSC BOM2"
VALUE"PSMNR58-30YLH"
PART_TYPE"SMLF"
MATERIAL"IC"
PART_NUMBER"BAMNR580000"
CDS_LMAN_SYM_OUTLINE"-150,200,150,-200"
NEEDS_NO_SIZE"TRUE"
CDS_LIB"pure_quanta";
"1"
$PN"1"3;
"4"
$PN"4"6;
"2"
$PN"2"3;
"5"
$PN"5"4;
"3"
$PN"3"3;
%"Q_RES"
"2","(-4825,1575)","0","pure_quanta","I45";
;
LOCATION"PR2530"
$SEC"1"
CDS_SEC"1"
ROOM"HSC BOM2"
MATERIAL"CHIP"
WATTAGE"1/16W"
TOLERANCE"1%"
VALUE"10"
PACK_TYPE"0402LF"
PART_NUMBER"CS01002FB07"
CDS_LIB"pure_quanta";
"A"
$PN"1"8;
"B"
$PN"2"11;
%"MOSFET_NCH_1D3S"
"1","(-5325,2300)","6","pure_quanta","I46";
;
LOCATION"PPQ6"
$SEC"1"
CDS_SEC"1"
ROOM"HSC BOM2"
PART_TYPE"SMLF"
VALUE"PSMNR58-30YLH"
MATERIAL"IC"
PART_NUMBER"BAMNR580000"
CDS_LIB"pure_quanta"
NEEDS_NO_SIZE"TRUE"
CDS_LMAN_SYM_OUTLINE"-150,200,150,-200";
"1"
$PN"1"3;
"4"
$PN"4"7;
"2"
$PN"2"3;
"5"
$PN"5"4;
"3"
$PN"3"3;
%"Q_RES"
"2","(-3975,1575)","0","pure_quanta","I47";
;
LOCATION"PR2531"
$SEC"1"
CDS_SEC"1"
ROOM"HSC BOM2"
TOLERANCE"1%"
WATTAGE"1/16W"
PACK_TYPE"0402LF"
MATERIAL"CHIP"
VALUE"10"
PART_NUMBER"CS01002FB07"
CDS_LIB"pure_quanta";
"A"
$PN"1"9;
"B"
$PN"2"11;
%"Q_RES"
"1","(-8250,2850)","0","pure_quanta","I5";
;
LOCATION"PR2523"
$SEC"1"
CDS_SEC"1"
ROOM"HSC BOM2"
MATERIAL"CHIP"
TOLERANCE"1%"
VALUE"1"
PART_NUMBER"CS-1002FB04"
CDS_LIB"pure_quanta"
PACK_TYPE"0402LF"
WATTAGE"1/16W";
"B"
$PN"2"24;
"A"
$PN"1"26;
%"Q_SP_RES4P"
"1","(-3525,3225)","0","pure_quanta","I52";
;
LOCATION"PR2534"
$SEC"1"
CDS_SEC"1"
ROOM"HSC BOM2"
WATTAGE"4W"
MATERIAL"CHIP"
TOLERANCE"1%"
VALUE"0.0003"
PART_TYPE"SMLF"
PART_NUMBER"SP_CS0000FFT09"
CDS_LMAN_SYM_OUTLINE"-150,75,150,-75"
CDS_LIB"pure_quanta"
NEEDS_NO_SIZE"TRUE";
"1A"
$PN"1A"1;
"2A"
$PN"2A"4;
"1B"
$PN"1B"45;
"2B"
$PN"2B"20;
%"Q_SP_RES4P"
"1","(-3525,3825)","0","pure_quanta","I53";
;
LOCATION"PR2533"
$SEC"1"
CDS_SEC"1"
ROOM"HSC BOM2"
TOLERANCE"1%"
WATTAGE"4W"
PART_TYPE"SMLF"
MATERIAL"CHIP"
VALUE"0.0003"
PART_NUMBER"SP_CS0000FFT09"
NEEDS_NO_SIZE"TRUE"
CDS_LMAN_SYM_OUTLINE"-150,75,150,-75"
CDS_LIB"pure_quanta";
"1A"
$PN"1A"1;
"2A"
$PN"2A"4;
"1B"
$PN"1B"15;
"2B"
$PN"2B"19;
%"Q_SP_RES4P"
"1","(-3525,4400)","0","pure_quanta","I54";
;
LOCATION"PR2532"
$SEC"1"
CDS_SEC"1"
MATERIAL"CHIP"
ROOM"HSC BOM2"
VALUE"0.0003"
WATTAGE"4W"
PART_TYPE"SMLF"
TOLERANCE"1%"
PART_NUMBER"SP_CS0000FFT09"
NEEDS_NO_SIZE"TRUE"
CDS_LMAN_SYM_OUTLINE"-150,75,150,-75"
CDS_LIB"pure_quanta";
"1A"
$PN"1A"1;
"2A"
$PN"2A"4;
"1B"
$PN"1B"44;
"2B"
$PN"2B"16;
%"Q_SP_RES4P"
"1","(-3500,4950)","0","pure_quanta","I55";
;
LOCATION"PR6001"
SEC"1"
TOLERANCE"1%"
ROOM"HSC BOM2"
VALUE"0.0003"
PART_TYPE"SMLF"
MATERIAL"CHIP"
WATTAGE"4W"
PART_NUMBER"SP_CS0000FFT09"
SEC_TYPE""
CDS_LIB"pure_quanta"
CDS_LMAN_SYM_OUTLINE"-150,75,150,-75"
NEEDS_NO_SIZE"TRUE";
"1A"
$PN"1A"1;
"2A"
$PN"2A"4;
"1B"
$PN"1B"14;
"2B"
$PN"2B"18;
%"UNIVERSAL_POWER"
"1","(-4875,5350)","0","pure_quanta_power","I56";
;
HDL_POWER"P12V_PSU"
ROOM"AUX_SW"
BOM_COST"MIO_VRD_SB"
CDS_LIB"pure_quanta_power";
"A"1;
%"GND"
"1","(-475,875)","0","pure_quanta_power","I59";
;
HDL_POWER"GND"
CDS_LIB"pure_quanta_power"
ROOM"VR_DDR1_POWER_STAGE"
SIZE"1B";
"A<SIZE-1..0>\NAC"2;
%"Q_RES"
"1","(-8250,3050)","0","pure_quanta","I6";
;
LOCATION"PR2521"
$SEC"1"
CDS_SEC"1"
ROOM"HSC BOM2"
TOLERANCE"1%"
VALUE"1"
MATERIAL"CHIP"
PART_NUMBER"CS-1002FB04"
CDS_LIB"pure_quanta"
PACK_TYPE"0402LF"
WATTAGE"1/16W";
"B"
$PN"2"22;
"A"
$PN"1"26;
%"Q_RES"
"2","(-3125,1575)","0","pure_quanta","I60";
;
LOCATION"PR2535"
$SEC"1"
CDS_SEC"1"
ROOM"HSC BOM2"
WATTAGE"1/16W"
MATERIAL"CHIP"
PACK_TYPE"0402LF"
VALUE"10"
TOLERANCE"1%"
PART_NUMBER"CS01002FB07"
CDS_LIB"pure_quanta";
"A"
$PN"1"10;
"B"
$PN"2"11;
%"MOSFET_NCH_1D3S"
"1","(-2700,2350)","6","pure_quanta","I61";
;
LOCATION"PPQ1"
SEC"1"
ROOM"HSC BOM2"
VALUE"PSMNR58-30YLH"
PART_TYPE"SMLF"
MATERIAL"IC"
PART_NUMBER"BAMNR580000"
SEC_TYPE""
NEEDS_NO_SIZE"TRUE"
CDS_LMAN_SYM_OUTLINE"-150,200,150,-200"
CDS_LIB"pure_quanta";
"1"
$PN"1"3;
"4"
$PN"4"10;
"2"
$PN"2"3;
"5"
$PN"5"4;
"3"
$PN"3"3;
%"Q_RES"
"2","(-2250,1575)","0","pure_quanta","I62";
;
LOCATION"PR2536"
$SEC"1"
CDS_SEC"1"
MATERIAL"CHIP"
PACK_TYPE"0402LF"
ROOM"HSC BOM2"
WATTAGE"1/16W"
TOLERANCE"1%"
VALUE"10"
PART_NUMBER"CS01002FB07"
CDS_LIB"pure_quanta";
"A"
$PN"1"12;
"B"
$PN"2"11;
%"Q_CAP"
"1","(-1650,1575)","0","pure_quanta","I63";
;
LOCATION"PC1750"
$SEC"1"
CDS_SEC"1"
ROOM"HSC BOM2"
VALUE"33NF"
VOLTAGE"25V"
TOLERANCE"10%"
MATERIAL"EMPTY"
PACK_TYPE"C0402"
PART_NUMBER"CH3334K1B00"
CDS_LIB"pure_quanta";
"B"
$PN"2"11;
"A"
$PN"1"3;
%"MOSFET_NCH_1D3S"
"1","(-1825,2375)","6","pure_quanta","I64";
;
LOCATION"PPQ2"
SEC"1"
PART_TYPE"SMLF"
VALUE"PSMNR58-30YLH"
ROOM"HSC BOM2"
MATERIAL"IC"
PART_NUMBER"BAMNR580000"
SEC_TYPE""
CDS_LIB"pure_quanta"
CDS_LMAN_SYM_OUTLINE"-150,200,150,-200"
NEEDS_NO_SIZE"TRUE";
"1"
$PN"1"3;
"4"
$PN"4"12;
"2"
$PN"2"3;
"5"
$PN"5"4;
"3"
$PN"3"3;
%"Q_RES"
"1","(-8250,2950)","0","pure_quanta","I7";
;
LOCATION"PR2522"
$SEC"1"
CDS_SEC"1"
MATERIAL"CHIP"
TOLERANCE"1%"
VALUE"1"
ROOM"HSC BOM2"
PART_NUMBER"CS-1002FB04"
CDS_LIB"pure_quanta"
PACK_TYPE"0402LF"
WATTAGE"1/16W";
"B"
$PN"2"23;
"A"
$PN"1"26;
%"Q_CAP"
"1","(-1175,1275)","0","pure_quanta","I70";
;
LOCATION"PC1751"
$SEC"1"
CDS_SEC"1"
ROOM"HSC BOM2"
PACK_TYPE"0402"
VOLTAGE"50V"
TOLERANCE"10%"
MATERIAL"EMPTY"
VALUE"1NF"
PART_NUMBER"CH21006KB16"
CDS_LIB"pure_quanta";
"B"
$PN"2"11;
"A"
$PN"1"46;
%"Q_RES"
"2","(-1175,1600)","0","pure_quanta","I71";
;
LOCATION"PR2537"
$SEC"1"
CDS_SEC"1"
PACK_TYPE"0402LF"
ROOM"HSC BOM2"
WATTAGE"1/16W"
TOLERANCE"1%"
VALUE"10"
MATERIAL"EMPTY"
PART_NUMBER"CS01002FB07"
CDS_LIB"pure_quanta";
"A"
$PN"1"3;
"B"
$PN"2"46;
%"SS15P3SM386A"
"1","(-475,1375)","1","pure_quanta","I72";
;
LOCATION"PD17"
$SEC"1"
CDS_SEC"1"
VALUE"SS15P3S-M3/86A"
MATERIAL"IC"
ROOM"HSC BOM2"
PART_TYPE"SMLF"
PART_NUMBER"BC015P3SZ00"
CDS_LIB"pure_quanta"
CDS_LMAN_SYM_OUTLINE"-125,100,125,-100"
NEEDS_NO_SIZE"TRUE";
"ANODE_2"
$PN"2"2;
"CATHODE"
$PN"K"3;
"ANODE_1"
$PN"1"2;
%"UNIVERSAL_POWER"
"1","(-850,2175)","0","pure_quanta_power","I73";
;
HDL_POWER"P12V_AUX"
BOM_COST"MIO_VRD_SB"
ROOM"AUX_SW"
CDS_LIB"pure_quanta_power";
"A"3;
%"Q_RES"
"2","(-875,3025)","0","pure_quanta","I74";
;
LOCATION"PR2538"
$SEC"1"
CDS_SEC"1"
PACK_TYPE"0402LF"
MATERIAL"CHIP"
WATTAGE"1/16W"
TOLERANCE"1%"
VALUE"10"
ROOM"HSC BOM2"
PART_NUMBER"CS01002FB07"
CDS_LIB"pure_quanta";
"A"
$PN"1"13;
"B"
$PN"2"47;
%"MOSFET_NCH_1D3S"
"1","(-375,3525)","6","pure_quanta","I75";
;
LOCATION"PPQ9"
$SEC"1"
CDS_SEC"1"
ROOM"HSC BOM2"
VALUE"PSMNR58-30YLH"
PART_TYPE"SMLF"
MATERIAL"IC"
PART_NUMBER"BAMNR580000"
NEEDS_NO_SIZE"TRUE"
CDS_LIB"pure_quanta"
CDS_LMAN_SYM_OUTLINE"-150,200,150,-200";
"1"
$PN"1"3;
"4"
$PN"4"13;
"2"
$PN"2"3;
"5"
$PN"5"5;
"3"
$PN"3"3;
%"UNIVERSAL_POWER"
"1","(-1750,5050)","0","pure_quanta_power","I77";
;
HDL_POWER"P12V_MAIN_R"
CDS_LIB"pure_quanta_power"
ROOM"AUX_SW"
BOM_COST"MIO_VRD_SB";
"A"4;
%"UNIVERSAL_POWER"
"1","(-1350,5300)","0","pure_quanta_power","I78";
;
HDL_POWER"P12V_MAIN_R_0"
ROOM"AUX_SW"
BOM_COST"MIO_VRD_SB"
CDS_LIB"pure_quanta_power";
"A"5;
%"MOSFET_NCH_1D3S"
"1","(-3575,2325)","6","pure_quanta","I79";
;
LOCATION"PPQ8"
$SEC"1"
CDS_SEC"1"
MATERIAL"IC"
ROOM"HSC BOM2"
PART_TYPE"SMLF"
VALUE"PSMNR58-30YLH"
PART_NUMBER"BAMNR580000"
CDS_LIB"pure_quanta"
NEEDS_NO_SIZE"TRUE"
CDS_LMAN_SYM_OUTLINE"-150,200,150,-200";
"1"
$PN"1"3;
"4"
$PN"4"9;
"2"
$PN"2"3;
"5"
$PN"5"4;
"3"
$PN"3"3;
%"Q_RES"
"1","(-8250,3150)","0","pure_quanta","I8";
;
LOCATION"PR2520"
$SEC"1"
CDS_SEC"1"
TOLERANCE"1%"
VALUE"1"
ROOM"HSC BOM2"
MATERIAL"CHIP"
PART_NUMBER"CS-1002FB04"
WATTAGE"1/16W"
PACK_TYPE"0402LF"
CDS_LIB"pure_quanta";
"B"
$PN"2"42;
"A"
$PN"1"26;
%"MOSFET_NCH_1D3S"
"1","(-4450,2325)","6","pure_quanta","I80";
;
LOCATION"PPQ7"
$SEC"1"
CDS_SEC"1"
ROOM"HSC BOM2"
VALUE"PSMNR58-30YLH"
PART_TYPE"SMLF"
MATERIAL"IC"
PART_NUMBER"BAMNR580000"
CDS_LMAN_SYM_OUTLINE"-150,200,150,-200"
NEEDS_NO_SIZE"TRUE"
CDS_LIB"pure_quanta";
"1"
$PN"1"3;
"4"
$PN"4"8;
"2"
$PN"2"3;
"5"
$PN"5"4;
"3"
$PN"3"3;
%"Q_SP_RES4P"
"1","(-3500,5250)","6","pure_quanta","I81";
;
LOCATION"PR6002"
SEC"1"
ROOM"HSC BOM2"
PART_TYPE"SMLF"
TOLERANCE"1%"
MATERIAL"CHIP"
VALUE"0.003"
WATTAGE"2W"
PART_NUMBER"SP_CS+003AFR00_1"
CDS_LIB"pure_quanta"
NEEDS_NO_SIZE"TRUE"
CDS_LMAN_SYM_OUTLINE"-150,75,150,-75"
SEC_TYPE"";
"1A"
$PN"1A"1;
"2A"
$PN"2A"5;
"1B"
$PN"1B"21;
"2B"
$PN"2B"17;
%"Q_RES"
"1","(-8275,4275)","0","pure_quanta","I82";
;
LOCATION"PR2514"
$SEC"1"
CDS_SEC"1"
MATERIAL"CHIP"
VALUE"10"
TOLERANCE"1%"
PACK_TYPE"0402LF"
ROOM"HSC BOM2"
WATTAGE"1/16W"
PART_NUMBER"CS01002FB07"
CDS_LIB"pure_quanta";
"B"
$PN"2"33;
"A"
$PN"1"32;
%"Q_RES"
"1","(-8250,3925)","0","pure_quanta","I83";
;
LOCATION"PR2515"
$SEC"1"
CDS_SEC"1"
VALUE"10"
TOLERANCE"1%"
MATERIAL"CHIP"
ROOM"HSC BOM2"
PART_NUMBER"CS01002FB07"
WATTAGE"1/16W"
PACK_TYPE"0402LF"
CDS_LIB"pure_quanta";
"B"
$PN"2"43;
"A"
$PN"1"31;
%"Q_RES"
"1","(-8250,3825)","0","pure_quanta","I84";
;
LOCATION"PR2516"
$SEC"1"
CDS_SEC"1"
VALUE"10"
MATERIAL"CHIP"
TOLERANCE"1%"
ROOM"HSC BOM2"
PART_NUMBER"CS01002FB07"
WATTAGE"1/16W"
PACK_TYPE"0402LF"
CDS_LIB"pure_quanta";
"B"
$PN"2"38;
"A"
$PN"1"31;
%"Q_RES"
"1","(-8250,3725)","0","pure_quanta","I85";
;
LOCATION"PR2517"
$SEC"1"
CDS_SEC"1"
VALUE"10"
MATERIAL"CHIP"
TOLERANCE"1%"
ROOM"HSC BOM2"
PART_NUMBER"CS01002FB07"
CDS_LIB"pure_quanta"
WATTAGE"1/16W"
PACK_TYPE"0402LF";
"B"
$PN"2"39;
"A"
$PN"1"31;
%"Q_RES"
"1","(-8250,3625)","0","pure_quanta","I86";
;
LOCATION"PR2518"
$SEC"1"
CDS_SEC"1"
VALUE"10"
MATERIAL"CHIP"
TOLERANCE"1%"
ROOM"HSC BOM2"
PART_NUMBER"CS01002FB07"
PACK_TYPE"0402LF"
WATTAGE"1/16W"
CDS_LIB"pure_quanta";
"B"
$PN"2"40;
"A"
$PN"1"31;
%"Q_RES"
"1","(-8250,3525)","0","pure_quanta","I87";
;
LOCATION"PR2519"
$SEC"1"
CDS_SEC"1"
VALUE"100"
MATERIAL"CHIP"
TOLERANCE"1%"
ROOM"HSC BOM2"
PART_NUMBER"CS11002FB07"
CDS_LIB"pure_quanta"
PACK_TYPE"0402LF"
WATTAGE"1/16W";
"B"
$PN"2"41;
"A"
$PN"1"31;
%"Q_RES"
"1","(-8225,2400)","0","pure_quanta","I88";
;
LOCATION"PR2524"
$SEC"1"
CDS_SEC"1"
ROOM"HSC BOM2"
VALUE"10"
MATERIAL"CHIP"
TOLERANCE"1%"
PART_NUMBER"CS01002FB07"
PACK_TYPE"0402LF"
WATTAGE"1/16W"
CDS_LIB"pure_quanta";
"B"
$PN"2"27;
"A"
$PN"1"25;
%"Q_RES"
"1","(-8225,2300)","0","pure_quanta","I89";
;
LOCATION"PR2525"
$SEC"1"
CDS_SEC"1"
ROOM"HSC BOM2"
VALUE"10"
TOLERANCE"1%"
MATERIAL"CHIP"
PART_NUMBER"CS01002FB07"
CDS_LIB"pure_quanta"
WATTAGE"1/16W"
PACK_TYPE"0402LF";
"B"
$PN"2"28;
"A"
$PN"1"25;
%"Q_RES"
"1","(-8225,2200)","0","pure_quanta","I90";
;
LOCATION"PR2526"
$SEC"1"
CDS_SEC"1"
ROOM"HSC BOM2"
TOLERANCE"1%"
MATERIAL"CHIP"
VALUE"10"
PART_NUMBER"CS01002FB07"
CDS_LIB"pure_quanta"
WATTAGE"1/16W"
PACK_TYPE"0402LF";
"B"
$PN"2"29;
"A"
$PN"1"25;
%"Q_RES"
"1","(-8225,2100)","0","pure_quanta","I91";
;
LOCATION"PR2527"
$SEC"1"
CDS_SEC"1"
ROOM"HSC BOM2"
TOLERANCE"1%"
VALUE"10"
MATERIAL"CHIP"
PART_NUMBER"CS01002FB07"
CDS_LIB"pure_quanta"
WATTAGE"1/16W"
PACK_TYPE"0402LF";
"B"
$PN"2"30;
"A"
$PN"1"25;
END.
